(kicad_pcb
	(version 20260206)
	(generator "pcbnew")
	(generator_version "10.0")
	(general
		(thickness 1.6)
		(legacy_teardrops no)
	)
	(paper "A4")
	(title_block
		(title "04192023_DAF0TMB3IC0_F0TG_MB_C_brd_V02_OCP.brd")
		(comment 1 "Grand Teton / footprints 2662-2667 of 8354")
	)
	(layers
		(0 "F.Cu" signal "TOP")
		(4 "In1.Cu" signal "GND")
		(6 "In2.Cu" signal "IN1")
		(8 "In3.Cu" signal "GND1")
		(10 "In4.Cu" signal "IN2")
		(12 "In5.Cu" signal "GND2")
		(14 "In6.Cu" signal "IN3")
		(16 "In7.Cu" signal "GND3")
		(18 "In8.Cu" signal "VCC")
		(20 "In9.Cu" signal "VCC1")
		(22 "In10.Cu" signal "GND4")
		(24 "In11.Cu" signal "IN4")
		(26 "In12.Cu" signal "GND5")
		(28 "In13.Cu" signal "IN5")
		(30 "In14.Cu" signal "GND6")
		(32 "In15.Cu" signal "IN6")
		(34 "In16.Cu" signal "GND7")
		(2 "B.Cu" signal "BOTTOM")
		(9 "F.Adhes" user "F.Adhesive")
		(11 "B.Adhes" user "B.Adhesive")
		(13 "F.Paste" user "Package Geometry/Pastemask Top")
		(15 "B.Paste" user "Package Geometry/Pastemask Bottom")
		(5 "F.SilkS" user "Ref Des/Silkscreen Top")
		(7 "B.SilkS" user "Ref Des/Silkscreen Bottom")
		(1 "F.Mask" user "Board Geometry/Soldermask Top")
		(3 "B.Mask" user "Board Geometry/Soldermask Bottom")
		(17 "Dwgs.User" user "User.Drawings")
		(19 "Cmts.User" user "User.Comments")
		(21 "Eco1.User" user "User.Eco1")
		(23 "Eco2.User" user "User.Eco2")
		(25 "Edge.Cuts" user "Board Geometry/Outline")
		(27 "Margin" user)
		(31 "F.CrtYd" user "Package Geometry/Place Bound Top")
		(29 "B.CrtYd" user "Package Geometry/Place Bound Bottom")
		(35 "F.Fab" user "Ref Des/Assembly Top")
		(33 "B.Fab" user "Ref Des/Assembly Bottom")
	)
	(footprint ""
		(layer "F.Cu")
		(at 137.971784 -48.325024 180)
		(property "Reference" "R6206"
			(at 0 0 180)
			(layer "F.SilkS")
			(hide yes)
			(effects
				(font
					(size 1.27 1.27)
				)
			)
		)
		(property "Value" ""
			(at 0 0 180)
			(layer "F.Fab")
			(effects
				(font
					(size 1.27 1.27)
				)
			)
		)
		(duplicate_pad_numbers_are_jumpers no)
		(fp_line
			(start 0.7874 0.4064)
			(end -0.7874 0.4064)
			(stroke
				(width 0.1524)
				(type default)
			)
			(layer "F.SilkS")
		)
		(fp_line
			(start 0.7874 -0.4064)
			(end 0.7874 0.4064)
			(stroke
				(width 0.1524)
				(type default)
			)
			(layer "F.SilkS")
		)
		(fp_line
			(start -0.7874 0.4064)
			(end -0.7874 -0.4064)
			(stroke
				(width 0.1524)
				(type default)
			)
			(layer "F.SilkS")
		)
		(fp_line
			(start -0.7874 -0.4064)
			(end 0.7874 -0.4064)
			(stroke
				(width 0.1524)
				(type default)
			)
			(layer "F.SilkS")
		)
		(fp_line
			(start 0.67945 0.3048)
			(end 0.120396 0.3048)
			(stroke
				(width 0.1)
				(type default)
			)
			(layer "F.Fab")
		)
		(fp_line
			(start 0.67945 -0.3048)
			(end 0.67945 0.3048)
			(stroke
				(width 0.1)
				(type default)
			)
			(layer "F.Fab")
		)
		(fp_line
			(start 0.12065 -0.2794)
			(end 0.12065 -0.3048)
			(stroke
				(width 0.1)
				(type default)
			)
			(layer "F.Fab")
		)
		(fp_line
			(start 0.12065 -0.3048)
			(end 0.67945 -0.3048)
			(stroke
				(width 0.1)
				(type default)
			)
			(layer "F.Fab")
		)
		(fp_line
			(start 0.120396 0.3048)
			(end 0.120396 0.2794)
			(stroke
				(width 0.1)
				(type default)
			)
			(layer "F.Fab")
		)
		(fp_line
			(start 0.120396 0.2794)
			(end -0.12065 0.2794)
			(stroke
				(width 0.1)
				(type default)
			)
			(layer "F.Fab")
		)
		(fp_line
			(start -0.12065 0.3048)
			(end -0.67945 0.3048)
			(stroke
				(width 0.1)
				(type default)
			)
			(layer "F.Fab")
		)
		(fp_line
			(start -0.12065 0.2794)
			(end -0.12065 0.3048)
			(stroke
				(width 0.1)
				(type default)
			)
			(layer "F.Fab")
		)
		(fp_line
			(start -0.12065 -0.2794)
			(end 0.12065 -0.2794)
			(stroke
				(width 0.1)
				(type default)
			)
			(layer "F.Fab")
		)
		(fp_line
			(start -0.12065 -0.305054)
			(end -0.12065 -0.2794)
			(stroke
				(width 0.1)
				(type default)
			)
			(layer "F.Fab")
		)
		(fp_line
			(start -0.67945 0.3048)
			(end -0.67945 -0.305054)
			(stroke
				(width 0.1)
				(type default)
			)
			(layer "F.Fab")
		)
		(fp_line
			(start -0.67945 -0.305054)
			(end -0.12065 -0.305054)
			(stroke
				(width 0.1)
				(type default)
			)
			(layer "F.Fab")
		)
		(pad "1" smd circle
			(at -0.40005 0 180)
			(size 0 0)
			(layers "F.Cu" "F.Mask" "F.Paste")
			(net "P3V3_AUX")
		)
		(pad "2" smd circle
			(at 0.40005 0 180)
			(size 0 0)
			(layers "F.Cu" "F.Mask" "F.Paste")
			(net "PU_CPU0_USB_HUB_RESERVED2")
		)
	)
	(footprint ""
		(layer "F.Cu")
		(at 461.41132 -38.565836)
		(property "Reference" "C36"
			(at 0 0 0)
			(layer "F.SilkS")
			(hide yes)
			(effects
				(font
					(size 1.27 1.27)
				)
			)
		)
		(property "Value" ""
			(at 0 0 0)
			(layer "F.Fab")
			(effects
				(font
					(size 1.27 1.27)
				)
			)
		)
		(duplicate_pad_numbers_are_jumpers no)
		(fp_line
			(start -0.7874 -0.4064)
			(end 0.7874 -0.4064)
			(stroke
				(width 0.1524)
				(type default)
			)
			(layer "F.SilkS")
		)
		(fp_line
			(start -0.7874 0.4064)
			(end -0.7874 -0.4064)
			(stroke
				(width 0.1524)
				(type default)
			)
			(layer "F.SilkS")
		)
		(fp_line
			(start 0.7874 -0.4064)
			(end 0.7874 0.4064)
			(stroke
				(width 0.1524)
				(type default)
			)
			(layer "F.SilkS")
		)
		(fp_line
			(start 0.7874 0.4064)
			(end -0.7874 0.4064)
			(stroke
				(width 0.1524)
				(type default)
			)
			(layer "F.SilkS")
		)
		(fp_line
			(start -0.67945 -0.305054)
			(end -0.12065 -0.305054)
			(stroke
				(width 0.1)
				(type default)
			)
			(layer "F.Fab")
		)
		(fp_line
			(start -0.67945 0.3048)
			(end -0.67945 -0.305054)
			(stroke
				(width 0.1)
				(type default)
			)
			(layer "F.Fab")
		)
		(fp_line
			(start -0.12065 -0.305054)
			(end -0.12065 -0.2794)
			(stroke
				(width 0.1)
				(type default)
			)
			(layer "F.Fab")
		)
		(fp_line
			(start -0.12065 -0.2794)
			(end 0.12065 -0.2794)
			(stroke
				(width 0.1)
				(type default)
			)
			(layer "F.Fab")
		)
		(fp_line
			(start -0.12065 0.2794)
			(end -0.12065 0.3048)
			(stroke
				(width 0.1)
				(type default)
			)
			(layer "F.Fab")
		)
		(fp_line
			(start -0.12065 0.3048)
			(end -0.67945 0.3048)
			(stroke
				(width 0.1)
				(type default)
			)
			(layer "F.Fab")
		)
		(fp_line
			(start 0.120396 0.2794)
			(end -0.12065 0.2794)
			(stroke
				(width 0.1)
				(type default)
			)
			(layer "F.Fab")
		)
		(fp_line
			(start 0.120396 0.3048)
			(end 0.120396 0.2794)
			(stroke
				(width 0.1)
				(type default)
			)
			(layer "F.Fab")
		)
		(fp_line
			(start 0.12065 -0.3048)
			(end 0.67945 -0.3048)
			(stroke
				(width 0.1)
				(type default)
			)
			(layer "F.Fab")
		)
		(fp_line
			(start 0.12065 -0.2794)
			(end 0.12065 -0.3048)
			(stroke
				(width 0.1)
				(type default)
			)
			(layer "F.Fab")
		)
		(fp_line
			(start 0.67945 -0.3048)
			(end 0.67945 0.3048)
			(stroke
				(width 0.1)
				(type default)
			)
			(layer "F.Fab")
		)
		(fp_line
			(start 0.67945 0.3048)
			(end 0.120396 0.3048)
			(stroke
				(width 0.1)
				(type default)
			)
			(layer "F.Fab")
		)
		(pad "1" smd circle
			(at -0.40005 0)
			(size 0 0)
			(layers "F.Cu" "F.Mask" "F.Paste")
			(net "P3V3_AUX")
		)
		(pad "2" smd circle
			(at 0.40005 0)
			(size 0 0)
			(layers "F.Cu" "F.Mask" "F.Paste")
			(net "GND")
		)
	)
	(footprint ""
		(layer "F.Cu")
		(at 118.379494 -167.06596 -90)
		(property "Reference" "PC317_7"
			(at 0 0 270)
			(layer "F.SilkS")
			(hide yes)
			(effects
				(font
					(size 1.27 1.27)
				)
			)
		)
		(property "Value" ""
			(at 0 0 270)
			(layer "F.Fab")
			(effects
				(font
					(size 1.27 1.27)
				)
			)
		)
		(duplicate_pad_numbers_are_jumpers no)
		(fp_line
			(start -0.7874 0.4064)
			(end -0.7874 -0.4064)
			(stroke
				(width 0.1524)
				(type default)
			)
			(layer "F.SilkS")
		)
		(fp_line
			(start 0.7874 0.4064)
			(end -0.7874 0.4064)
			(stroke
				(width 0.1524)
				(type default)
			)
			(layer "F.SilkS")
		)
		(fp_line
			(start -0.7874 -0.4064)
			(end 0.7874 -0.4064)
			(stroke
				(width 0.1524)
				(type default)
			)
			(layer "F.SilkS")
		)
		(fp_line
			(start 0.7874 -0.4064)
			(end 0.7874 0.4064)
			(stroke
				(width 0.1524)
				(type default)
			)
			(layer "F.SilkS")
		)
		(fp_line
			(start -0.67945 0.3048)
			(end -0.67945 -0.305054)
			(stroke
				(width 0.1)
				(type default)
			)
			(layer "F.Fab")
		)
		(fp_line
			(start -0.12065 0.3048)
			(end -0.67945 0.3048)
			(stroke
				(width 0.1)
				(type default)
			)
			(layer "F.Fab")
		)
		(fp_line
			(start 0.120396 0.3048)
			(end 0.120396 0.2794)
			(stroke
				(width 0.1)
				(type default)
			)
			(layer "F.Fab")
		)
		(fp_line
			(start 0.67945 0.3048)
			(end 0.120396 0.3048)
			(stroke
				(width 0.1)
				(type default)
			)
			(layer "F.Fab")
		)
		(fp_line
			(start -0.12065 0.2794)
			(end -0.12065 0.3048)
			(stroke
				(width 0.1)
				(type default)
			)
			(layer "F.Fab")
		)
		(fp_line
			(start 0.120396 0.2794)
			(end -0.12065 0.2794)
			(stroke
				(width 0.1)
				(type default)
			)
			(layer "F.Fab")
		)
		(fp_line
			(start -0.12065 -0.2794)
			(end 0.12065 -0.2794)
			(stroke
				(width 0.1)
				(type default)
			)
			(layer "F.Fab")
		)
		(fp_line
			(start 0.12065 -0.2794)
			(end 0.12065 -0.3048)
			(stroke
				(width 0.1)
				(type default)
			)
			(layer "F.Fab")
		)
		(fp_line
			(start 0.12065 -0.3048)
			(end 0.67945 -0.3048)
			(stroke
				(width 0.1)
				(type default)
			)
			(layer "F.Fab")
		)
		(fp_line
			(start 0.67945 -0.3048)
			(end 0.67945 0.3048)
			(stroke
				(width 0.1)
				(type default)
			)
			(layer "F.Fab")
		)
		(fp_line
			(start -0.67945 -0.305054)
			(end -0.12065 -0.305054)
			(stroke
				(width 0.1)
				(type default)
			)
			(layer "F.Fab")
		)
		(fp_line
			(start -0.12065 -0.305054)
			(end -0.12065 -0.2794)
			(stroke
				(width 0.1)
				(type default)
			)
			(layer "F.Fab")
		)
		(pad "1" smd circle
			(at -0.40005 0 270)
			(size 0 0)
			(layers "F.Cu" "F.Mask" "F.Paste")
			(net "PVDDCR_CPU0_P1_VCCS")
		)
		(pad "2" smd circle
			(at 0.40005 0 270)
			(size 0 0)
			(layers "F.Cu" "F.Mask" "F.Paste")
			(net "GND")
		)
	)
	(footprint ""
		(layer "F.Cu")
		(at 103.601266 -401.329906 -90)
		(property "Reference" "U12"
			(at 0.837184 -3.221482 90)
			(unlocked yes)
			(layer "F.SilkS")
			(effects
				(font
					(size 0.7874 0.5842)
					(thickness 0.1524)
				)
				(justify left)
			)
		)
		(property "Value" ""
			(at 0 0 270)
			(layer "F.Fab")
			(effects
				(font
					(size 1.27 1.27)
				)
			)
		)
		(duplicate_pad_numbers_are_jumpers no)
		(fp_line
			(start -1.8288 2.500122)
			(end 1.8288 2.500122)
			(stroke
				(width 0.1524)
				(type default)
			)
			(layer "F.SilkS")
		)
		(fp_line
			(start 1.8288 2.500122)
			(end 1.8288 -2.500122)
			(stroke
				(width 0.1524)
				(type default)
			)
			(layer "F.SilkS")
		)
		(fp_line
			(start 0 -1.4224)
			(end -1.077722 -2.500122)
			(stroke
				(width 0.1524)
				(type default)
			)
			(layer "F.SilkS")
		)
		(fp_line
			(start -1.8288 -2.500122)
			(end -1.8288 2.500122)
			(stroke
				(width 0.1524)
				(type default)
			)
			(layer "F.SilkS")
		)
		(fp_line
			(start -1.077722 -2.500122)
			(end -1.8288 -2.500122)
			(stroke
				(width 0.1524)
				(type default)
			)
			(layer "F.SilkS")
		)
		(fp_line
			(start 1.077722 -2.500122)
			(end 0 -1.4224)
			(stroke
				(width 0.1524)
				(type default)
			)
			(layer "F.SilkS")
		)
		(fp_line
			(start 1.8288 -2.500122)
			(end 1.077722 -2.500122)
			(stroke
				(width 0.1524)
				(type default)
			)
			(layer "F.SilkS")
		)
		(fp_poly
			(pts
				(xy -4.932934 -2.31648) (xy -4.932934 -1.30048) (xy -3.916934 -1.80848)
			)
			(stroke
				(width 0)
				(type default)
			)
			(fill yes)
			(layer "F.SilkS")
		)
		(fp_line
			(start -1.999996 2.500122)
			(end 1.999996 2.500122)
			(stroke
				(width 0.1)
				(type default)
			)
			(layer "F.Fab")
		)
		(fp_line
			(start 1.999996 2.500122)
			(end 1.999996 -2.500122)
			(stroke
				(width 0.1)
				(type default)
			)
			(layer "F.Fab")
		)
		(fp_line
			(start -1.999996 -2.500122)
			(end -1.999996 2.500122)
			(stroke
				(width 0.1)
				(type default)
			)
			(layer "F.Fab")
		)
		(fp_line
			(start 1.999996 -2.500122)
			(end -1.999996 -2.500122)
			(stroke
				(width 0.1)
				(type default)
			)
			(layer "F.Fab")
		)
		(fp_poly
			(pts
				(xy -4.5085 -2.413) (xy -4.5085 -1.397) (xy -3.4925 -1.905)
			)
			(stroke
				(width 0)
				(type default)
			)
			(fill yes)
			(layer "F.Fab")
		)
		(pad "1" smd rect
			(at -2.599944 -1.905 180)
			(size 0.889 1.27)
			(layers "F.Cu" "F.Mask" "F.Paste")
			(net "Net_10845")
		)
		(pad "2" smd rect
			(at -2.599944 -0.635 180)
			(size 0.889 1.27)
			(layers "F.Cu" "F.Mask" "F.Paste")
			(net "Net_10844")
		)
		(pad "3" smd rect
			(at -2.599944 0.635 180)
			(size 0.889 1.27)
			(layers "F.Cu" "F.Mask" "F.Paste")
			(net "U12_E2")
		)
		(pad "4" smd rect
			(at -2.599944 1.905 180)
			(size 0.889 1.27)
			(layers "F.Cu" "F.Mask" "F.Paste")
			(net "GND")
		)
		(pad "5" smd rect
			(at 2.599944 1.905 180)
			(size 0.889 1.27)
			(layers "F.Cu" "F.Mask" "F.Paste")
			(net "SMB_RT_CPU1_P0_ROM_SDA")
		)
		(pad "6" smd rect
			(at 2.599944 0.635 180)
			(size 0.889 1.27)
			(layers "F.Cu" "F.Mask" "F.Paste")
			(net "SMB_RT_CPU1_P0_ROM_SCL")
		)
		(pad "7" smd rect
			(at 2.599944 -0.635 180)
			(size 0.889 1.27)
			(layers "F.Cu" "F.Mask" "F.Paste")
			(net "GND")
		)
		(pad "8" smd rect
			(at 2.599944 -1.905 180)
			(size 0.889 1.27)
			(layers "F.Cu" "F.Mask" "F.Paste")
			(net "P1V8_CPU1_RT_1D")
		)
	)
	(footprint ""
		(layer "F.Cu")
		(at 321.980306 -335.09458 -90)
		(property "Reference" "PC118_3"
			(at 0 0 270)
			(layer "F.SilkS")
			(hide yes)
			(effects
				(font
					(size 1.27 1.27)
				)
			)
		)
		(property "Value" ""
			(at 0 0 270)
			(layer "F.Fab")
			(effects
				(font
					(size 1.27 1.27)
				)
			)
		)
		(duplicate_pad_numbers_are_jumpers no)
		(fp_line
			(start -0.7874 0.4064)
			(end -0.7874 -0.4064)
			(stroke
				(width 0.1524)
				(type default)
			)
			(layer "F.SilkS")
		)
		(fp_line
			(start 0.7874 0.4064)
			(end -0.7874 0.4064)
			(stroke
				(width 0.1524)
				(type default)
			)
			(layer "F.SilkS")
		)
		(fp_line
			(start -0.7874 -0.4064)
			(end 0.7874 -0.4064)
			(stroke
				(width 0.1524)
				(type default)
			)
			(layer "F.SilkS")
		)
		(fp_line
			(start 0.7874 -0.4064)
			(end 0.7874 0.4064)
			(stroke
				(width 0.1524)
				(type default)
			)
			(layer "F.SilkS")
		)
		(fp_line
			(start -0.67945 0.3048)
			(end -0.67945 -0.305054)
			(stroke
				(width 0.1)
				(type default)
			)
			(layer "F.Fab")
		)
		(fp_line
			(start -0.12065 0.3048)
			(end -0.67945 0.3048)
			(stroke
				(width 0.1)
				(type default)
			)
			(layer "F.Fab")
		)
		(fp_line
			(start 0.120396 0.3048)
			(end 0.120396 0.2794)
			(stroke
				(width 0.1)
				(type default)
			)
			(layer "F.Fab")
		)
		(fp_line
			(start 0.67945 0.3048)
			(end 0.120396 0.3048)
			(stroke
				(width 0.1)
				(type default)
			)
			(layer "F.Fab")
		)
		(fp_line
			(start -0.12065 0.2794)
			(end -0.12065 0.3048)
			(stroke
				(width 0.1)
				(type default)
			)
			(layer "F.Fab")
		)
		(fp_line
			(start 0.120396 0.2794)
			(end -0.12065 0.2794)
			(stroke
				(width 0.1)
				(type default)
			)
			(layer "F.Fab")
		)
		(fp_line
			(start -0.12065 -0.2794)
			(end 0.12065 -0.2794)
			(stroke
				(width 0.1)
				(type default)
			)
			(layer "F.Fab")
		)
		(fp_line
			(start 0.12065 -0.2794)
			(end 0.12065 -0.3048)
			(stroke
				(width 0.1)
				(type default)
			)
			(layer "F.Fab")
		)
		(fp_line
			(start 0.12065 -0.3048)
			(end 0.67945 -0.3048)
			(stroke
				(width 0.1)
				(type default)
			)
			(layer "F.Fab")
		)
		(fp_line
			(start 0.67945 -0.3048)
			(end 0.67945 0.3048)
			(stroke
				(width 0.1)
				(type default)
			)
			(layer "F.Fab")
		)
		(fp_line
			(start -0.67945 -0.305054)
			(end -0.12065 -0.305054)
			(stroke
				(width 0.1)
				(type default)
			)
			(layer "F.Fab")
		)
		(fp_line
			(start -0.12065 -0.305054)
			(end -0.12065 -0.2794)
			(stroke
				(width 0.1)
				(type default)
			)
			(layer "F.Fab")
		)
		(pad "1" smd circle
			(at -0.40005 0 270)
			(size 0 0)
			(layers "F.Cu" "F.Mask" "F.Paste")
			(net "SW_P12V_AUX_PVDDCR_CPU1_P0_FLT")
		)
		(pad "2" smd circle
			(at 0.40005 0 270)
			(size 0 0)
			(layers "F.Cu" "F.Mask" "F.Paste")
			(net "GND")
		)
	)
	(footprint ""
		(layer "F.Cu")
		(at 432.308 -407.4922)
		(property "Reference" "R1476"
			(at 0 0 0)
			(layer "F.SilkS")
			(hide yes)
			(effects
				(font
					(size 1.27 1.27)
				)
			)
		)
		(property "Value" ""
			(at 0 0 0)
			(layer "F.Fab")
			(effects
				(font
					(size 1.27 1.27)
				)
			)
		)
		(duplicate_pad_numbers_are_jumpers no)
		(fp_line
			(start -0.32512 -0.175006)
			(end 0.32512 -0.175006)
			(stroke
				(width 0.1)
				(type default)
			)
			(layer "F.Fab")
		)
		(fp_line
			(start -0.32512 0.175006)
			(end -0.32512 -0.175006)
			(stroke
				(width 0.1)
				(type default)
			)
			(layer "F.Fab")
		)
		(fp_line
			(start 0.32512 -0.175006)
			(end 0.32512 0.175006)
			(stroke
				(width 0.1)
				(type default)
			)
			(layer "F.Fab")
		)
		(fp_line
			(start 0.32512 0.175006)
			(end -0.32512 0.175006)
			(stroke
				(width 0.1)
				(type default)
			)
			(layer "F.Fab")
		)
		(pad "1" smd rect
			(at -0.2667 0)
			(size 0.3048 0.381)
			(layers "F.Cu" "F.Mask" "F.Paste")
			(net "P1V8_CPU0_RT_1D")
		)
		(pad "2" smd rect
			(at 0.2667 0 180)
			(size 0.3048 0.381)
			(layers "F.Cu" "F.Mask" "F.Paste")
			(net "JTAG_TDI_RT_CPU0_P2")
		)
	)
)
